# T6G (Grand Teton) — schematic netlist excerpt (pin names and nets, part order shuffled) for the footprints in the layout excerpt that follows; sources: Cadence DE-HDL packaged netlist, KiCad conversion of 04192023_DAF0TMB3IC0_F0TG_MB_C_brd_V02_OCP.brd

C2205  Q_CAP  22UF 4V 20% X6S  pkg C0402  page 69 : A = PVDDCR_CPU1_P0 ; B = GND
C2186  Q_CAP  22UF 4V 20% X6S  pkg C0402  page 69 : A = PVDDCR_CPU0_P0 ; B = GND

(kicad_pcb
	(version 20260206)
	(generator "pcbnew")
	(generator_version "10.0")
	(general
		(thickness 1.6)
		(legacy_teardrops no)
	)
	(paper "A4")
	(title_block
		(title "04192023_DAF0TMB3IC0_F0TG_MB_C_brd_V02_OCP.brd")
		(comment 1 "Grand Teton / footprints 5793-5794 of 8354")
	)
	(layers
		(0 "F.Cu" signal "TOP")
		(4 "In1.Cu" signal "GND")
		(6 "In2.Cu" signal "IN1")
		(8 "In3.Cu" signal "GND1")
		(10 "In4.Cu" signal "IN2")
		(12 "In5.Cu" signal "GND2")
		(14 "In6.Cu" signal "IN3")
		(16 "In7.Cu" signal "GND3")
		(18 "In8.Cu" signal "VCC")
		(20 "In9.Cu" signal "VCC1")
		(22 "In10.Cu" signal "GND4")
		(24 "In11.Cu" signal "IN4")
		(26 "In12.Cu" signal "GND5")
		(28 "In13.Cu" signal "IN5")
		(30 "In14.Cu" signal "GND6")
		(32 "In15.Cu" signal "IN6")
		(34 "In16.Cu" signal "GND7")
		(2 "B.Cu" signal "BOTTOM")
		(9 "F.Adhes" user "F.Adhesive")
		(11 "B.Adhes" user "B.Adhesive")
		(13 "F.Paste" user "Package Geometry/Pastemask Top")
		(15 "B.Paste" user "Package Geometry/Pastemask Bottom")
		(5 "F.SilkS" user "Ref Des/Silkscreen Top")
		(7 "B.SilkS" user "Ref Des/Silkscreen Bottom")
		(1 "F.Mask" user "Board Geometry/Soldermask Top")
		(3 "B.Mask" user "Board Geometry/Soldermask Bottom")
		(17 "Dwgs.User" user "User.Drawings")
		(19 "Cmts.User" user "User.Comments")
		(21 "Eco1.User" user "User.Eco1")
		(23 "Eco2.User" user "User.Eco2")
		(25 "Edge.Cuts" user "Board Geometry/Outline")
		(27 "Margin" user)
		(31 "F.CrtYd" user "Package Geometry/Place Bound Top")
		(29 "B.CrtYd" user "Package Geometry/Place Bound Bottom")
		(35 "F.Fab" user "Ref Des/Assembly Top")
		(33 "B.Fab" user "Ref Des/Assembly Bottom")
	)
	(footprint ""
		(layer "B.Cu")
		(at 350.596454 -267.52931)
		(property "Reference" "C2205"
			(at 0 0 0)
			(layer "B.SilkS")
			(hide yes)
			(effects
				(font
					(size 1.27 1.27)
				)
				(justify mirror)
			)
		)
		(property "Value" ""
			(at 0 0 0)
			(layer "B.Fab")
			(effects
				(font
					(size 1.27 1.27)
				)
				(justify mirror)
			)
		)
		(duplicate_pad_numbers_are_jumpers no)
		(fp_line
			(start -0.7874 -0.4064)
			(end -0.7874 0.4064)
			(stroke
				(width 0.1524)
				(type default)
			)
			(layer "B.SilkS")
		)
		(fp_line
			(start -0.7874 0.4064)
			(end 0.7874 0.4064)
			(stroke
				(width 0.1524)
				(type default)
			)
			(layer "B.SilkS")
		)
		(fp_line
			(start 0.7874 -0.4064)
			(end -0.7874 -0.4064)
			(stroke
				(width 0.1524)
				(type default)
			)
			(layer "B.SilkS")
		)
		(fp_line
			(start 0.7874 0.4064)
			(end 0.7874 -0.4064)
			(stroke
				(width 0.1524)
				(type default)
			)
			(layer "B.SilkS")
		)
		(fp_line
			(start -0.67945 -0.3048)
			(end -0.67945 0.3048)
			(stroke
				(width 0.1)
				(type default)
			)
			(layer "B.Fab")
		)
		(fp_line
			(start -0.67945 0.3048)
			(end -0.120396 0.3048)
			(stroke
				(width 0.1)
				(type default)
			)
			(layer "B.Fab")
		)
		(fp_line
			(start -0.12065 -0.3048)
			(end -0.67945 -0.3048)
			(stroke
				(width 0.1)
				(type default)
			)
			(layer "B.Fab")
		)
		(fp_line
			(start -0.12065 -0.2794)
			(end -0.12065 -0.3048)
			(stroke
				(width 0.1)
				(type default)
			)
			(layer "B.Fab")
		)
		(fp_line
			(start -0.120396 0.2794)
			(end 0.12065 0.2794)
			(stroke
				(width 0.1)
				(type default)
			)
			(layer "B.Fab")
		)
		(fp_line
			(start -0.120396 0.3048)
			(end -0.120396 0.2794)
			(stroke
				(width 0.1)
				(type default)
			)
			(layer "B.Fab")
		)
		(fp_line
			(start 0.12065 -0.305054)
			(end 0.12065 -0.2794)
			(stroke
				(width 0.1)
				(type default)
			)
			(layer "B.Fab")
		)
		(fp_line
			(start 0.12065 -0.2794)
			(end -0.12065 -0.2794)
			(stroke
				(width 0.1)
				(type default)
			)
			(layer "B.Fab")
		)
		(fp_line
			(start 0.12065 0.2794)
			(end 0.12065 0.3048)
			(stroke
				(width 0.1)
				(type default)
			)
			(layer "B.Fab")
		)
		(fp_line
			(start 0.12065 0.3048)
			(end 0.67945 0.3048)
			(stroke
				(width 0.1)
				(type default)
			)
			(layer "B.Fab")
		)
		(fp_line
			(start 0.67945 -0.305054)
			(end 0.12065 -0.305054)
			(stroke
				(width 0.1)
				(type default)
			)
			(layer "B.Fab")
		)
		(fp_line
			(start 0.67945 0.3048)
			(end 0.67945 -0.305054)
			(stroke
				(width 0.1)
				(type default)
			)
			(layer "B.Fab")
		)
		(pad "1" smd circle
			(at 0.40005 0 180)
			(size 0 0)
			(layers "B.Cu" "B.Mask" "B.Paste")
			(net "PVDDCR_CPU1_P0")
		)
		(pad "2" smd circle
			(at -0.40005 0 180)
			(size 0 0)
			(layers "B.Cu" "B.Mask" "B.Paste")
			(net "GND")
		)
	)
	(footprint ""
		(layer "B.Cu")
		(at 359.740454 -249.87631 90)
		(property "Reference" "C2186"
			(at 0 0 90)
			(layer "B.SilkS")
			(hide yes)
			(effects
				(font
					(size 1.27 1.27)
				)
				(justify mirror)
			)
		)
		(property "Value" ""
			(at 0 0 90)
			(layer "B.Fab")
			(effects
				(font
					(size 1.27 1.27)
				)
				(justify mirror)
			)
		)
		(duplicate_pad_numbers_are_jumpers no)
		(fp_line
			(start 0.7874 -0.4064)
			(end -0.7874 -0.4064)
			(stroke
				(width 0.1524)
				(type default)
			)
			(layer "B.SilkS")
		)
		(fp_line
			(start -0.7874 -0.4064)
			(end -0.7874 0.4064)
			(stroke
				(width 0.1524)
				(type default)
			)
			(layer "B.SilkS")
		)
		(fp_line
			(start 0.7874 0.4064)
			(end 0.7874 -0.4064)
			(stroke
				(width 0.1524)
				(type default)
			)
			(layer "B.SilkS")
		)
		(fp_line
			(start -0.7874 0.4064)
			(end 0.7874 0.4064)
			(stroke
				(width 0.1524)
				(type default)
			)
			(layer "B.SilkS")
		)
		(fp_line
			(start 0.67945 -0.305054)
			(end 0.12065 -0.305054)
			(stroke
				(width 0.1)
				(type default)
			)
			(layer "B.Fab")
		)
		(fp_line
			(start 0.12065 -0.305054)
			(end 0.12065 -0.2794)
			(stroke
				(width 0.1)
				(type default)
			)
			(layer "B.Fab")
		)
		(fp_line
			(start -0.12065 -0.3048)
			(end -0.67945 -0.3048)
			(stroke
				(width 0.1)
				(type default)
			)
			(layer "B.Fab")
		)
		(fp_line
			(start -0.67945 -0.3048)
			(end -0.67945 0.3048)
			(stroke
				(width 0.1)
				(type default)
			)
			(layer "B.Fab")
		)
		(fp_line
			(start 0.12065 -0.2794)
			(end -0.12065 -0.2794)
			(stroke
				(width 0.1)
				(type default)
			)
			(layer "B.Fab")
		)
		(fp_line
			(start -0.12065 -0.2794)
			(end -0.12065 -0.3048)
			(stroke
				(width 0.1)
				(type default)
			)
			(layer "B.Fab")
		)
		(fp_line
			(start 0.12065 0.2794)
			(end 0.12065 0.3048)
			(stroke
				(width 0.1)
				(type default)
			)
			(layer "B.Fab")
		)
		(fp_line
			(start -0.120396 0.2794)
			(end 0.12065 0.2794)
			(stroke
				(width 0.1)
				(type default)
			)
			(layer "B.Fab")
		)
		(fp_line
			(start 0.67945 0.3048)
			(end 0.67945 -0.305054)
			(stroke
				(width 0.1)
				(type default)
			)
			(layer "B.Fab")
		)
		(fp_line
			(start 0.12065 0.3048)
			(end 0.67945 0.3048)
			(stroke
				(width 0.1)
				(type default)
			)
			(layer "B.Fab")
		)
		(fp_line
			(start -0.120396 0.3048)
			(end -0.120396 0.2794)
			(stroke
				(width 0.1)
				(type default)
			)
			(layer "B.Fab")
		)
		(fp_line
			(start -0.67945 0.3048)
			(end -0.120396 0.3048)
			(stroke
				(width 0.1)
				(type default)
			)
			(layer "B.Fab")
		)
		(pad "1" smd circle
			(at 0.40005 0 270)
			(size 0 0)
			(layers "B.Cu" "B.Mask" "B.Paste")
			(net "PVDDCR_CPU0_P0")
		)
		(pad "2" smd circle
			(at -0.40005 0 270)
			(size 0 0)
			(layers "B.Cu" "B.Mask" "B.Paste")
			(net "GND")
		)
	)
)
